FILE_TYPE = MULTI_PHYS_TABLE;

PART 'BNO080_LGA_28'
CLASS = IC 

{========================================================================================}
:CLS_PN           |VALUE        = JEDEC_TYPE             |ALT_SYMBOLS              |DESCRIPTION                 				                                                    		|CPN_STATUS    ;
{========================================================================================}
 'A246-00001-FB'  |'BNO080'     = 'LGA28_205X150_P0197'  |'(LGA28_205X150_P0197)'  |'IC,BNO080,SIP,32-BIT ARM CORTEX,TRIAXIAL ACCELEROMETER,TRIAXIAL GYROSCOPE,MAGNETOMETER,SMT,LGA-28'     |'' 
 'A246-00002-FB'  |'BNO085'     = 'LGA28_205X150_P0197'  |'(LGA28_205X150_P0197)'  |'IC,BNO085,SIP,32-BIT ARM CORTEX,TRIAXIAL ACCELEROMETER,TRIAXIAL GYROSCOPE,MAGNETOMETER,SMT,LGA-28'     |'' 

END_PART

END.

